#ISCELL
  mstr_standard drawing *
  *
#ISCELL
  mstr_standard synonym *
  page1_4p
